(kicad_pcb
	(version 20241229)
	(generator "pcbnew")
	(generator_version "9.0")
	(general
		(thickness 1.63)
		(legacy_teardrops no)
	)
	(paper "A4")
	(title_block
		(title "CM4 Baseboard")
		(date "2026-01-05")
		(rev "1.1.1")
		(company "Antmicro Ltd")
		(comment 1 "www.antmicro.com")
		(comment 9 "footprints 299-302 of 506")
	)
	(layers
		(0 "F.Cu" signal)
		(4 "In1.Cu" power)
		(6 "In2.Cu" power)
		(8 "In3.Cu" signal)
		(10 "In4.Cu" signal)
		(2 "B.Cu" signal)
		(9 "F.Adhes" user "F.Adhesive")
		(11 "B.Adhes" user "B.Adhesive")
		(13 "F.Paste" user)
		(15 "B.Paste" user)
		(5 "F.SilkS" user "F.Silkscreen")
		(7 "B.SilkS" user "B.Silkscreen")
		(1 "F.Mask" user)
		(3 "B.Mask" user)
		(17 "Dwgs.User" user "User.Drawings")
		(19 "Cmts.User" user "User.Comments")
		(21 "Eco1.User" user "User.Eco1")
		(23 "Eco2.User" user "User.Eco2")
		(25 "Edge.Cuts" user)
		(27 "Margin" user)
		(31 "F.CrtYd" user "F.Courtyard")
		(29 "B.CrtYd" user "B.Courtyard")
		(35 "F.Fab" user)
		(33 "B.Fab" user)
	)
	(footprint "antmicro-footprints:Spacer_Drill3.7mm_H3mm_9774030151R"
		(layer "F.Cu")
		(at 80.520961 128.314 90)
		(descr "Spacer M=3 h=3mm fi=5.1mm")
		(property "Reference" "H203"
			(at -1.511 4.004039 270)
			(layer "F.SilkS")
			(effects
				(font
					(size 0.7 0.7)
					(thickness 0.15)
				)
				(justify left bottom)
			)
		)
		(property "Value" "Spacer_Drill3.7mm_H3mm_9774030151R"
			(at 0 4 90)
			(layer "F.Fab")
			(effects
				(font
					(size 0.7 0.7)
					(thickness 0.15)
				)
				(justify left bottom)
			)
		)
		(property "Datasheet" "https://www.we-online.com/catalog/datasheet/9774030151.pdf"
			(at 0 0 90)
			(layer "F.Fab")
			(hide yes)
			(effects
				(font
					(size 1.27 1.27)
					(thickness 0.15)
				)
			)
		)
		(property "Manufacturer" "Würth Elektronik"
			(at 0 0 90)
			(unlocked yes)
			(layer "F.Fab")
			(hide yes)
			(effects
				(font
					(size 1 1)
					(thickness 0.15)
				)
			)
		)
		(property "MPN" "9774030151R"
			(at 0 0 90)
			(unlocked yes)
			(layer "F.Fab")
			(hide yes)
			(effects
				(font
					(size 1 1)
					(thickness 0.15)
				)
			)
		)
		(property "Author" "Antmicro"
			(at 0 0 90)
			(unlocked yes)
			(layer "F.Fab")
			(hide yes)
			(effects
				(font
					(size 1 1)
					(thickness 0.15)
				)
			)
		)
		(property "License" "Apache-2.0"
			(at 0 0 90)
			(unlocked yes)
			(layer "F.Fab")
			(hide yes)
			(effects
				(font
					(size 1 1)
					(thickness 0.15)
				)
			)
		)
		(sheetname "/Compute module/")
		(sheetfile "compute-module.kicad_sch")
		(solder_paste_margin_ratio -1)
		(attr smd)
		(fp_circle
			(center 0 0)
			(end 3.05 0)
			(stroke
				(width 0.05)
				(type solid)
			)
			(fill no)
			(layer "F.CrtYd")
		)
		(fp_circle
			(center 0 0)
			(end 2.6 0)
			(stroke
				(width 0.15)
				(type solid)
			)
			(fill no)
			(layer "F.Fab")
		)
		(fp_text user "${REFERENCE}"
			(at -9.6 6.5 90)
			(layer "F.Fab")
			(effects
				(font
					(size 0.7 0.7)
					(thickness 0.15)
				)
				(justify left bottom)
			)
		)
		(fp_text user "License: Apache-2.0"
			(at -9.6 8.9 90)
			(layer "F.Fab")
			(effects
				(font
					(size 0.7 0.7)
					(thickness 0.15)
				)
				(justify left bottom)
			)
		)
		(fp_text user "Author: Antmicro"
			(at -9.6 7.7 90)
			(layer "F.Fab")
			(effects
				(font
					(size 0.7 0.7)
					(thickness 0.15)
				)
				(justify left bottom)
			)
		)
		(pad "" smd custom
			(at -1.7 -1.7 90)
			(size 0.62 0.62)
			(layers "F.Paste")
			(thermal_bridge_angle 90)
			(options
				(clearance outline)
				(anchor circle)
			)
			(primitives
				(gr_arc
					(start -0.250195 1.279127)
					(mid 0.285453 0.294389)
					(end 1.266786 -0.24747)
					(width 0.2)
				)
				(gr_arc
					(start -0.34334 1.279127)
					(mid 0.218448 0.232561)
					(end 1.259603 -0.339191)
					(width 0.2)
				)
				(gr_arc
					(start -0.436309 1.279127)
					(mid 0.152481 0.169693)
					(end 1.255279 -0.431435)
					(width 0.2)
				)
				(gr_arc
					(start -0.529126 1.279127)
					(mid 0.087542 0.105784)
					(end 1.253811 -0.524161)
					(width 0.2)
				)
				(gr_arc
					(start -0.621807 1.279127)
					(mid 0.0309 0.033527)
					(end 1.275473 -0.621136)
					(width 0.2)
				)
				(gr_arc
					(start -0.71437 1.279127)
					(mid -0.037758 -0.026651)
					(end 1.263664 -0.711602)
					(width 0.2)
				)
				(gr_arc
					(start -0.806826 1.279127)
					(mid -0.105837 -0.087395)
					(end 1.253435 -0.802342)
					(width 0.2)
				)
				(gr_arc
					(start -0.899187 1.279127)
					(mid -0.165236 -0.156885)
					(end 1.267475 -0.897258)
					(width 0.2)
				)
				(gr_arc
					(start -0.991463 1.279127)
					(mid -0.228522 -0.222449)
					(end 1.270645 -0.990112)
					(width 0.2)
				)
				(gr_arc
					(start -1.083663 1.279127)
					(mid -0.294507 -0.285313)
					(end 1.266278 -1.081674)
					(width 0.2)
				)
				(gr_line
					(start 1.279127 -0.250195)
					(end 1.279127 -1.083663)
					(width 0.2)
				)
				(gr_line
					(start -0.250195 1.279127)
					(end -1.083663 1.279127)
					(width 0.2)
				)
			)
		)
		(pad "" smd custom
			(at -1.7 1.7 180)
			(size 0.62 0.62)
			(layers "F.Paste")
			(thermal_bridge_angle 90)
			(options
				(clearance outline)
				(anchor circle)
			)
			(primitives
				(gr_arc
					(start -0.250195 1.279127)
					(mid 0.285453 0.294389)
					(end 1.266786 -0.24747)
					(width 0.2)
				)
				(gr_arc
					(start -0.34334 1.279127)
					(mid 0.218448 0.232561)
					(end 1.259603 -0.339191)
					(width 0.2)
				)
				(gr_arc
					(start -0.436309 1.279127)
					(mid 0.152481 0.169693)
					(end 1.255279 -0.431435)
					(width 0.2)
				)
				(gr_arc
					(start -0.529126 1.279127)
					(mid 0.087542 0.105784)
					(end 1.253811 -0.524161)
					(width 0.2)
				)
				(gr_arc
					(start -0.621807 1.279127)
					(mid 0.0309 0.033527)
					(end 1.275473 -0.621136)
					(width 0.2)
				)
				(gr_arc
					(start -0.71437 1.279127)
					(mid -0.037758 -0.026651)
					(end 1.263664 -0.711602)
					(width 0.2)
				)
				(gr_arc
					(start -0.806826 1.279127)
					(mid -0.105837 -0.087395)
					(end 1.253435 -0.802342)
					(width 0.2)
				)
				(gr_arc
					(start -0.899187 1.279127)
					(mid -0.165236 -0.156885)
					(end 1.267475 -0.897258)
					(width 0.2)
				)
				(gr_arc
					(start -0.991463 1.279127)
					(mid -0.228522 -0.222449)
					(end 1.270645 -0.990112)
					(width 0.2)
				)
				(gr_arc
					(start -1.083663 1.279127)
					(mid -0.294507 -0.285313)
					(end 1.266278 -1.081674)
					(width 0.2)
				)
				(gr_line
					(start 1.279127 -0.250195)
					(end 1.279127 -1.083663)
					(width 0.2)
				)
				(gr_line
					(start -0.250195 1.279127)
					(end -1.083663 1.279127)
					(width 0.2)
				)
			)
		)
		(pad "" smd custom
			(at 1.7 -1.7)
			(size 0.62 0.62)
			(layers "F.Paste")
			(thermal_bridge_angle 90)
			(options
				(clearance outline)
				(anchor circle)
			)
			(primitives
				(gr_arc
					(start -0.250195 1.279127)
					(mid 0.285453 0.294389)
					(end 1.266786 -0.24747)
					(width 0.2)
				)
				(gr_arc
					(start -0.34334 1.279127)
					(mid 0.218448 0.232561)
					(end 1.259603 -0.339191)
					(width 0.2)
				)
				(gr_arc
					(start -0.436309 1.279127)
					(mid 0.152481 0.169693)
					(end 1.255279 -0.431435)
					(width 0.2)
				)
				(gr_arc
					(start -0.529126 1.279127)
					(mid 0.087542 0.105784)
					(end 1.253811 -0.524161)
					(width 0.2)
				)
				(gr_arc
					(start -0.621807 1.279127)
					(mid 0.0309 0.033527)
					(end 1.275473 -0.621136)
					(width 0.2)
				)
				(gr_arc
					(start -0.71437 1.279127)
					(mid -0.037758 -0.026651)
					(end 1.263664 -0.711602)
					(width 0.2)
				)
				(gr_arc
					(start -0.806826 1.279127)
					(mid -0.105837 -0.087395)
					(end 1.253435 -0.802342)
					(width 0.2)
				)
				(gr_arc
					(start -0.899187 1.279127)
					(mid -0.165236 -0.156885)
					(end 1.267475 -0.897258)
					(width 0.2)
				)
				(gr_arc
					(start -0.991463 1.279127)
					(mid -0.228522 -0.222449)
					(end 1.270645 -0.990112)
					(width 0.2)
				)
				(gr_arc
					(start -1.083663 1.279127)
					(mid -0.294507 -0.285313)
					(end 1.266278 -1.081674)
					(width 0.2)
				)
				(gr_line
					(start 1.279127 -0.250195)
					(end 1.279127 -1.083663)
					(width 0.2)
				)
				(gr_line
					(start -0.250195 1.279127)
					(end -1.083663 1.279127)
					(width 0.2)
				)
			)
		)
		(pad "" smd custom
			(at 1.7 1.7 270)
			(size 0.62 0.62)
			(layers "F.Paste")
			(thermal_bridge_angle 90)
			(options
				(clearance outline)
				(anchor circle)
			)
			(primitives
				(gr_arc
					(start -0.250195 1.279127)
					(mid 0.285453 0.294389)
					(end 1.266786 -0.24747)
					(width 0.2)
				)
				(gr_arc
					(start -0.34334 1.279127)
					(mid 0.218448 0.232561)
					(end 1.259603 -0.339191)
					(width 0.2)
				)
				(gr_arc
					(start -0.436309 1.279127)
					(mid 0.152481 0.169693)
					(end 1.255279 -0.431435)
					(width 0.2)
				)
				(gr_arc
					(start -0.529126 1.279127)
					(mid 0.087542 0.105784)
					(end 1.253811 -0.524161)
					(width 0.2)
				)
				(gr_arc
					(start -0.621807 1.279127)
					(mid 0.0309 0.033527)
					(end 1.275473 -0.621136)
					(width 0.2)
				)
				(gr_arc
					(start -0.71437 1.279127)
					(mid -0.037758 -0.026651)
					(end 1.263664 -0.711602)
					(width 0.2)
				)
				(gr_arc
					(start -0.806826 1.279127)
					(mid -0.105837 -0.087395)
					(end 1.253435 -0.802342)
					(width 0.2)
				)
				(gr_arc
					(start -0.899187 1.279127)
					(mid -0.165236 -0.156885)
					(end 1.267475 -0.897258)
					(width 0.2)
				)
				(gr_arc
					(start -0.991463 1.279127)
					(mid -0.228522 -0.222449)
					(end 1.270645 -0.990112)
					(width 0.2)
				)
				(gr_arc
					(start -1.083663 1.279127)
					(mid -0.294507 -0.285313)
					(end 1.266278 -1.081674)
					(width 0.2)
				)
				(gr_line
					(start 1.279127 -0.250195)
					(end 1.279127 -1.083663)
					(width 0.2)
				)
				(gr_line
					(start -0.250195 1.279127)
					(end -1.083663 1.279127)
					(width 0.2)
				)
			)
		)
		(pad "1" thru_hole circle
			(at 0 0 90)
			(size 6 6)
			(drill 3.7)
			(layers "*.Cu" "*.Mask")
			(remove_unused_layers no)
			(net 3 "GND")
			(pintype "passive")
		)
	)
	(footprint "antmicro-footprints:C_0402_1005Metric"
		(layer "F.Cu")
		(at 69.817962 176.8165 -90)
		(descr "Capacitor SMD 0402")
		(tags "capacitor SMD 0402")
		(property "Reference" "C808"
			(at 1.8735 -0.432038 180)
			(layer "F.SilkS")
			(effects
				(font
					(size 0.7 0.65)
					(thickness 0.15)
				)
				(justify right bottom)
			)
		)
		(property "Value" "C_2u2_0402"
			(at -1.022927 2.155213 90)
			(layer "F.Fab")
			(effects
				(font
					(size 0.7 0.7)
					(thickness 0.15)
				)
				(justify right bottom)
			)
		)
		(property "Datasheet" "https://product.tdk.com/en/search/capacitor/ceramic/mlcc/info?part_no=C1005X5R1A225K050BC"
			(at 0 0 270)
			(layer "F.Fab")
			(hide yes)
			(effects
				(font
					(size 1.27 1.27)
					(thickness 0.15)
				)
			)
		)
		(property "MPN" "C1005X5R1A225K050BC"
			(at 0 0 270)
			(unlocked yes)
			(layer "F.Fab")
			(hide yes)
			(effects
				(font
					(size 1 1)
					(thickness 0.15)
				)
			)
		)
		(property "Manufacturer" "TDK"
			(at 0 0 270)
			(unlocked yes)
			(layer "F.Fab")
			(hide yes)
			(effects
				(font
					(size 1 1)
					(thickness 0.15)
				)
			)
		)
		(property "License" "Apache-2.0"
			(at 0 0 270)
			(unlocked yes)
			(layer "F.Fab")
			(hide yes)
			(effects
				(font
					(size 1 1)
					(thickness 0.15)
				)
			)
		)
		(property "Author" "Antmicro"
			(at 0 0 270)
			(unlocked yes)
			(layer "F.Fab")
			(hide yes)
			(effects
				(font
					(size 1 1)
					(thickness 0.15)
				)
			)
		)
		(property "Val" "2u2"
			(at 0 0 270)
			(unlocked yes)
			(layer "F.Fab")
			(hide yes)
			(effects
				(font
					(size 1 1)
					(thickness 0.15)
				)
			)
		)
		(property "Voltage" ""
			(at 0 0 270)
			(unlocked yes)
			(layer "F.Fab")
			(hide yes)
			(effects
				(font
					(size 1 1)
					(thickness 0.15)
				)
			)
		)
		(property "Dielectric" ""
			(at 0 0 270)
			(unlocked yes)
			(layer "F.Fab")
			(hide yes)
			(effects
				(font
					(size 1 1)
					(thickness 0.15)
				)
			)
		)
		(sheetname "/Peripherals/")
		(sheetfile "peripherals.kicad_sch")
		(attr smd)
		(fp_rect
			(start -0.925 -0.47)
			(end 0.925 0.47)
			(stroke
				(width 0.05)
				(type default)
			)
			(fill no)
			(layer "F.CrtYd")
		)
		(fp_line
			(start -0.494 0.248)
			(end -0.494 -0.25)
			(stroke
				(width 0.15)
				(type solid)
			)
			(layer "F.Fab")
		)
		(fp_line
			(start 0.504 0.248)
			(end -0.494 0.248)
			(stroke
				(width 0.15)
				(type solid)
			)
			(layer "F.Fab")
		)
		(fp_line
			(start -0.494 -0.25)
			(end 0.504 -0.25)
			(stroke
				(width 0.15)
				(type solid)
			)
			(layer "F.Fab")
		)
		(fp_line
			(start 0.504 -0.25)
			(end 0.504 0.248)
			(stroke
				(width 0.15)
				(type solid)
			)
			(layer "F.Fab")
		)
		(fp_text user "License: Apache-2.0"
			(at -0.939 5.799 270)
			(layer "F.Fab")
			(effects
				(font
					(size 0.7 0.7)
					(thickness 0.15)
				)
				(justify left bottom)
			)
		)
		(fp_text user "${REFERENCE}"
			(at -0.939 4.599 270)
			(layer "F.Fab")
			(effects
				(font
					(size 0.7 0.7)
					(thickness 0.15)
				)
				(justify left bottom)
			)
		)
		(fp_text user "Author: Antmicro"
			(at -0.939 3.399 270)
			(layer "F.Fab")
			(effects
				(font
					(size 0.7 0.7)
					(thickness 0.15)
				)
				(justify left bottom)
			)
		)
		(pad "1" smd roundrect
			(at -0.48 0 270)
			(size 0.59 0.64)
			(layers "F.Cu" "F.Mask" "F.Paste")
			(roundrect_rratio 0.25)
			(net 94 "Net-(U801-TVDD_IN)")
			(pintype "passive")
		)
		(pad "2" smd roundrect
			(at 0.48 0 270)
			(size 0.59 0.64)
			(layers "F.Cu" "F.Mask" "F.Paste")
			(roundrect_rratio 0.25)
			(net 3 "GND")
			(pintype "passive")
		)
	)
	(footprint "antmicro-footprints:C_0402_1005Metric"
		(layer "F.Cu")
		(at 66.142962 171.6165 180)
		(descr "Capacitor SMD 0402")
		(tags "capacitor SMD 0402")
		(property "Reference" "C809"
			(at 0.842962 -0.1835 0)
			(layer "F.SilkS")
			(effects
				(font
					(size 0.7 0.7)
					(thickness 0.15)
				)
				(justify right bottom)
			)
		)
		(property "Value" "C_100n_0402"
			(at -1.022927 2.155213 0)
			(layer "F.Fab")
			(effects
				(font
					(size 0.7 0.7)
					(thickness 0.15)
				)
				(justify right bottom)
			)
		)
		(property "Datasheet" "https://www.murata.com/products/productdetail?partno=GRM155R61H104KE14%23"
			(at 0 0 180)
			(layer "F.Fab")
			(hide yes)
			(effects
				(font
					(size 1.27 1.27)
					(thickness 0.15)
				)
			)
		)
		(property "MPN" "GRM155R61H104KE14D"
			(at 0 0 180)
			(unlocked yes)
			(layer "F.Fab")
			(hide yes)
			(effects
				(font
					(size 1 1)
					(thickness 0.15)
				)
			)
		)
		(property "Manufacturer" "Murata"
			(at 0 0 180)
			(unlocked yes)
			(layer "F.Fab")
			(hide yes)
			(effects
				(font
					(size 1 1)
					(thickness 0.15)
				)
			)
		)
		(property "License" "Apache-2.0"
			(at 0 0 180)
			(unlocked yes)
			(layer "F.Fab")
			(hide yes)
			(effects
				(font
					(size 1 1)
					(thickness 0.15)
				)
			)
		)
		(property "Author" "Antmicro"
			(at 0 0 180)
			(unlocked yes)
			(layer "F.Fab")
			(hide yes)
			(effects
				(font
					(size 1 1)
					(thickness 0.15)
				)
			)
		)
		(property "Val" "100n"
			(at 0 0 180)
			(unlocked yes)
			(layer "F.Fab")
			(hide yes)
			(effects
				(font
					(size 1 1)
					(thickness 0.15)
				)
			)
		)
		(property "Voltage" "50V"
			(at 0 0 180)
			(unlocked yes)
			(layer "F.Fab")
			(hide yes)
			(effects
				(font
					(size 1 1)
					(thickness 0.15)
				)
			)
		)
		(property "Dielectric" "X5R"
			(at 0 0 180)
			(unlocked yes)
			(layer "F.Fab")
			(hide yes)
			(effects
				(font
					(size 1 1)
					(thickness 0.15)
				)
			)
		)
		(sheetname "/Peripherals/")
		(sheetfile "peripherals.kicad_sch")
		(attr smd)
		(fp_rect
			(start -0.925 -0.47)
			(end 0.925 0.47)
			(stroke
				(width 0.05)
				(type default)
			)
			(fill no)
			(layer "F.CrtYd")
		)
		(fp_line
			(start 0.504 0.248)
			(end -0.494 0.248)
			(stroke
				(width 0.15)
				(type solid)
			)
			(layer "F.Fab")
		)
		(fp_line
			(start 0.504 -0.25)
			(end 0.504 0.248)
			(stroke
				(width 0.15)
				(type solid)
			)
			(layer "F.Fab")
		)
		(fp_line
			(start -0.494 0.248)
			(end -0.494 -0.25)
			(stroke
				(width 0.15)
				(type solid)
			)
			(layer "F.Fab")
		)
		(fp_line
			(start -0.494 -0.25)
			(end 0.504 -0.25)
			(stroke
				(width 0.15)
				(type solid)
			)
			(layer "F.Fab")
		)
		(fp_text user "License: Apache-2.0"
			(at -0.939 5.799 180)
			(layer "F.Fab")
			(effects
				(font
					(size 0.7 0.7)
					(thickness 0.15)
				)
				(justify left bottom)
			)
		)
		(fp_text user "Author: Antmicro"
			(at -0.939 3.399 180)
			(layer "F.Fab")
			(effects
				(font
					(size 0.7 0.7)
					(thickness 0.15)
				)
				(justify left bottom)
			)
		)
		(fp_text user "${REFERENCE}"
			(at -0.939 4.599 180)
			(layer "F.Fab")
			(effects
				(font
					(size 0.7 0.7)
					(thickness 0.15)
				)
				(justify left bottom)
			)
		)
		(pad "1" smd roundrect
			(at -0.48 0 180)
			(size 0.59 0.64)
			(layers "F.Cu" "F.Mask" "F.Paste")
			(roundrect_rratio 0.25)
			(net 95 "Net-(U801-V_{DD(VMID)})")
			(pintype "passive")
		)
		(pad "2" smd roundrect
			(at 0.48 0 180)
			(size 0.59 0.64)
			(layers "F.Cu" "F.Mask" "F.Paste")
			(roundrect_rratio 0.25)
			(net 3 "GND")
			(pintype "passive")
		)
	)
	(footprint "antmicro-footprints:R_0402_1005Metric"
		(layer "F.Cu")
		(at 89.042962 157.4415 90)
		(descr "Resistor SMD 0402")
		(tags "resistor SMD 0402")
		(property "Reference" "R238"
			(at -3.685 0.435 90)
			(layer "F.SilkS")
			(effects
				(font
					(size 0.7 0.7)
					(thickness 0.15)
				)
				(justify left bottom)
			)
		)
		(property "Value" "R_10k_0402"
			(at -1.011843 1.772047 90)
			(layer "F.Fab")
			(effects
				(font
					(size 0.7 0.7)
					(thickness 0.15)
				)
				(justify left bottom)
			)
		)
		(property "Datasheet" "https://www.bourns.com/docs/product-datasheets/cr.pdf"
			(at 0 0 90)
			(layer "F.Fab")
			(hide yes)
			(effects
				(font
					(size 1.27 1.27)
					(thickness 0.15)
				)
			)
		)
		(property "Manufacturer" "Bourns"
			(at 0 0 90)
			(unlocked yes)
			(layer "F.Fab")
			(hide yes)
			(effects
				(font
					(size 1 1)
					(thickness 0.15)
				)
			)
		)
		(property "MPN" "CR0402-FX-1002GLF"
			(at 0 0 90)
			(unlocked yes)
			(layer "F.Fab")
			(hide yes)
			(effects
				(font
					(size 1 1)
					(thickness 0.15)
				)
			)
		)
		(property "Val" "10k"
			(at 0 0 90)
			(unlocked yes)
			(layer "F.Fab")
			(hide yes)
			(effects
				(font
					(size 1 1)
					(thickness 0.15)
				)
			)
		)
		(property "License" "Apache-2.0"
			(at 0 0 90)
			(unlocked yes)
			(layer "F.Fab")
			(hide yes)
			(effects
				(font
					(size 1 1)
					(thickness 0.15)
				)
			)
		)
		(property "Author" "Antmicro"
			(at 0 0 90)
			(unlocked yes)
			(layer "F.Fab")
			(hide yes)
			(effects
				(font
					(size 1 1)
					(thickness 0.15)
				)
			)
		)
		(property "Tolerance" "1%"
			(at 0 0 90)
			(unlocked yes)
			(layer "F.Fab")
			(hide yes)
			(effects
				(font
					(size 1 1)
					(thickness 0.15)
				)
			)
		)
		(sheetname "/Compute module/")
		(sheetfile "compute-module.kicad_sch")
		(attr smd)
		(fp_rect
			(start -0.925 -0.47)
			(end 0.925 0.47)
			(stroke
				(width 0.05)
				(type default)
			)
			(fill no)
			(layer "F.CrtYd")
		)
		(fp_rect
			(start -0.5 -0.25)
			(end 0.5 0.25)
			(stroke
				(width 0.15)
				(type solid)
			)
			(fill no)
			(layer "F.Fab")
		)
		(fp_text user "Author: Antmicro"
			(at -0.95 4.169 90)
			(layer "F.Fab")
			(effects
				(font
					(size 0.7 0.7)
					(thickness 0.15)
				)
				(justify left bottom)
			)
		)
		(fp_text user "${REFERENCE}"
			(at -0.95 3.168 90)
			(layer "F.Fab")
			(effects
				(font
					(size 0.7 0.7)
					(thickness 0.15)
				)
				(justify left bottom)
			)
		)
		(fp_text user "License: Apache-2.0"
			(at -0.95 5.169 90)
			(layer "F.Fab")
			(effects
				(font
					(size 0.7 0.7)
					(thickness 0.15)
				)
				(justify left bottom)
			)
		)
		(pad "1" smd roundrect
			(at -0.48 0 90)
			(size 0.59 0.64)
			(layers "F.Cu" "F.Mask" "F.Paste")
			(roundrect_rratio 0.25)
			(net 18 "V_{IO}")
			(pintype "passive")
		)
		(pad "2" smd roundrect
			(at 0.48 0 90)
			(size 0.59 0.64)
			(layers "F.Cu" "F.Mask" "F.Paste")
			(roundrect_rratio 0.25)
			(net 235 "/Compute module/GPIO.23")
			(pintype "passive")
		)
	)
)
